(kicad_pcb
	(version 20260206)
	(generator "pcbnew")
	(generator_version "10.0")
	(general
		(thickness 1.6)
		(legacy_teardrops no)
	)
	(paper "A4")
	(title_block
		(title "01162023_DA0F0TEBIF0_F0T_Expander_BD_F_brd_V02_OCP.brd")
		(comment 1 "Grand Teton / footprints 4281-4288 of 9728")
	)
	(layers
		(0 "F.Cu" signal "TOP")
		(4 "In1.Cu" signal "GND")
		(6 "In2.Cu" signal "VCC")
		(8 "In3.Cu" signal "VCC1")
		(10 "In4.Cu" signal "GND1")
		(12 "In5.Cu" signal "IN1")
		(14 "In6.Cu" signal "GND2")
		(16 "In7.Cu" signal "IN2")
		(18 "In8.Cu" signal "GND3")
		(20 "In9.Cu" signal "IN3")
		(22 "In10.Cu" signal "GND4")
		(24 "In11.Cu" signal "IN4")
		(26 "In12.Cu" signal "GND5")
		(28 "In13.Cu" signal "IN5")
		(30 "In14.Cu" signal "GND6")
		(32 "In15.Cu" signal "IN6")
		(34 "In16.Cu" signal "GND7")
		(2 "B.Cu" signal "BOTTOM")
		(9 "F.Adhes" user "F.Adhesive")
		(11 "B.Adhes" user "B.Adhesive")
		(13 "F.Paste" user "Package Geometry/Pastemask Top")
		(15 "B.Paste" user "Package Geometry/Pastemask Bottom")
		(5 "F.SilkS" user "Ref Des/Silkscreen Top")
		(7 "B.SilkS" user "Ref Des/Silkscreen Bottom")
		(1 "F.Mask" user "Board Geometry/Soldermask Top")
		(3 "B.Mask" user "Board Geometry/Soldermask Bottom")
		(17 "Dwgs.User" user "User.Drawings")
		(19 "Cmts.User" user "User.Comments")
		(21 "Eco1.User" user "User.Eco1")
		(23 "Eco2.User" user "User.Eco2")
		(25 "Edge.Cuts" user "Board Geometry/Outline")
		(27 "Margin" user)
		(31 "F.CrtYd" user "Package Geometry/Place Bound Top")
		(29 "B.CrtYd" user "Package Geometry/Place Bound Bottom")
		(35 "F.Fab" user "Ref Des/Assembly Top")
		(33 "B.Fab" user "Ref Des/Assembly Bottom")
	)
	(footprint ""
		(layer "F.Cu")
		(at 143.226282 -37.929566 90)
		(property "Reference" "R5555"
			(at 0 0 90)
			(layer "F.SilkS")
			(hide yes)
			(effects
				(font
					(size 1.27 1.27)
				)
			)
		)
		(property "Value" ""
			(at 0 0 90)
			(layer "F.Fab")
			(effects
				(font
					(size 1.27 1.27)
				)
			)
		)
		(duplicate_pad_numbers_are_jumpers no)
		(fp_line
			(start 0.7874 -0.4064)
			(end 0.7874 0.4064)
			(stroke
				(width 0.1524)
				(type default)
			)
			(layer "F.SilkS")
		)
		(fp_line
			(start -0.7874 -0.4064)
			(end 0.7874 -0.4064)
			(stroke
				(width 0.1524)
				(type default)
			)
			(layer "F.SilkS")
		)
		(fp_line
			(start 0.7874 0.4064)
			(end -0.7874 0.4064)
			(stroke
				(width 0.1524)
				(type default)
			)
			(layer "F.SilkS")
		)
		(fp_line
			(start -0.7874 0.4064)
			(end -0.7874 -0.4064)
			(stroke
				(width 0.1524)
				(type default)
			)
			(layer "F.SilkS")
		)
		(fp_line
			(start -0.12065 -0.305054)
			(end -0.12065 -0.2794)
			(stroke
				(width 0.1)
				(type default)
			)
			(layer "F.Fab")
		)
		(fp_line
			(start -0.67945 -0.305054)
			(end -0.12065 -0.305054)
			(stroke
				(width 0.1)
				(type default)
			)
			(layer "F.Fab")
		)
		(fp_line
			(start 0.67945 -0.3048)
			(end 0.67945 0.3048)
			(stroke
				(width 0.1)
				(type default)
			)
			(layer "F.Fab")
		)
		(fp_line
			(start 0.12065 -0.3048)
			(end 0.67945 -0.3048)
			(stroke
				(width 0.1)
				(type default)
			)
			(layer "F.Fab")
		)
		(fp_line
			(start 0.12065 -0.2794)
			(end 0.12065 -0.3048)
			(stroke
				(width 0.1)
				(type default)
			)
			(layer "F.Fab")
		)
		(fp_line
			(start -0.12065 -0.2794)
			(end 0.12065 -0.2794)
			(stroke
				(width 0.1)
				(type default)
			)
			(layer "F.Fab")
		)
		(fp_line
			(start 0.120396 0.2794)
			(end -0.12065 0.2794)
			(stroke
				(width 0.1)
				(type default)
			)
			(layer "F.Fab")
		)
		(fp_line
			(start -0.12065 0.2794)
			(end -0.12065 0.3048)
			(stroke
				(width 0.1)
				(type default)
			)
			(layer "F.Fab")
		)
		(fp_line
			(start 0.67945 0.3048)
			(end 0.120396 0.3048)
			(stroke
				(width 0.1)
				(type default)
			)
			(layer "F.Fab")
		)
		(fp_line
			(start 0.120396 0.3048)
			(end 0.120396 0.2794)
			(stroke
				(width 0.1)
				(type default)
			)
			(layer "F.Fab")
		)
		(fp_line
			(start -0.12065 0.3048)
			(end -0.67945 0.3048)
			(stroke
				(width 0.1)
				(type default)
			)
			(layer "F.Fab")
		)
		(fp_line
			(start -0.67945 0.3048)
			(end -0.67945 -0.305054)
			(stroke
				(width 0.1)
				(type default)
			)
			(layer "F.Fab")
		)
		(pad "1" smd circle
			(at -0.40005 0 90)
			(size 0 0)
			(layers "F.Cu" "F.Mask" "F.Paste")
			(net "SSD5_AUX_P3V3_EN_R")
		)
		(pad "2" smd circle
			(at 0.40005 0 90)
			(size 0 0)
			(layers "F.Cu" "F.Mask" "F.Paste")
			(net "SSD5_AUX_P3V3_EN")
		)
	)
	(footprint ""
		(layer "F.Cu")
		(at 278.87295 -22.867366 90)
		(property "Reference" "C3935"
			(at 0 0 90)
			(layer "F.SilkS")
			(hide yes)
			(effects
				(font
					(size 1.27 1.27)
				)
			)
		)
		(property "Value" ""
			(at 0 0 90)
			(layer "F.Fab")
			(effects
				(font
					(size 1.27 1.27)
				)
			)
		)
		(duplicate_pad_numbers_are_jumpers no)
		(fp_line
			(start 0.7874 -0.4064)
			(end 0.7874 0.4064)
			(stroke
				(width 0.1524)
				(type default)
			)
			(layer "F.SilkS")
		)
		(fp_line
			(start -0.7874 -0.4064)
			(end 0.7874 -0.4064)
			(stroke
				(width 0.1524)
				(type default)
			)
			(layer "F.SilkS")
		)
		(fp_line
			(start 0.7874 0.4064)
			(end -0.7874 0.4064)
			(stroke
				(width 0.1524)
				(type default)
			)
			(layer "F.SilkS")
		)
		(fp_line
			(start -0.7874 0.4064)
			(end -0.7874 -0.4064)
			(stroke
				(width 0.1524)
				(type default)
			)
			(layer "F.SilkS")
		)
		(fp_line
			(start -0.12065 -0.305054)
			(end -0.12065 -0.2794)
			(stroke
				(width 0.1)
				(type default)
			)
			(layer "F.Fab")
		)
		(fp_line
			(start -0.67945 -0.305054)
			(end -0.12065 -0.305054)
			(stroke
				(width 0.1)
				(type default)
			)
			(layer "F.Fab")
		)
		(fp_line
			(start 0.67945 -0.3048)
			(end 0.67945 0.3048)
			(stroke
				(width 0.1)
				(type default)
			)
			(layer "F.Fab")
		)
		(fp_line
			(start 0.12065 -0.3048)
			(end 0.67945 -0.3048)
			(stroke
				(width 0.1)
				(type default)
			)
			(layer "F.Fab")
		)
		(fp_line
			(start 0.12065 -0.2794)
			(end 0.12065 -0.3048)
			(stroke
				(width 0.1)
				(type default)
			)
			(layer "F.Fab")
		)
		(fp_line
			(start -0.12065 -0.2794)
			(end 0.12065 -0.2794)
			(stroke
				(width 0.1)
				(type default)
			)
			(layer "F.Fab")
		)
		(fp_line
			(start 0.120396 0.2794)
			(end -0.12065 0.2794)
			(stroke
				(width 0.1)
				(type default)
			)
			(layer "F.Fab")
		)
		(fp_line
			(start -0.12065 0.2794)
			(end -0.12065 0.3048)
			(stroke
				(width 0.1)
				(type default)
			)
			(layer "F.Fab")
		)
		(fp_line
			(start 0.67945 0.3048)
			(end 0.120396 0.3048)
			(stroke
				(width 0.1)
				(type default)
			)
			(layer "F.Fab")
		)
		(fp_line
			(start 0.120396 0.3048)
			(end 0.120396 0.2794)
			(stroke
				(width 0.1)
				(type default)
			)
			(layer "F.Fab")
		)
		(fp_line
			(start -0.12065 0.3048)
			(end -0.67945 0.3048)
			(stroke
				(width 0.1)
				(type default)
			)
			(layer "F.Fab")
		)
		(fp_line
			(start -0.67945 0.3048)
			(end -0.67945 -0.305054)
			(stroke
				(width 0.1)
				(type default)
			)
			(layer "F.Fab")
		)
		(pad "1" smd circle
			(at -0.40005 0 90)
			(size 0 0)
			(layers "F.Cu" "F.Mask" "F.Paste")
			(net "P12V_SSD9")
		)
		(pad "2" smd circle
			(at 0.40005 0 90)
			(size 0 0)
			(layers "F.Cu" "F.Mask" "F.Paste")
			(net "GND")
		)
	)
	(footprint ""
		(layer "F.Cu")
		(at 131.404868 -350.098614 90)
		(property "Reference" "C2272"
			(at 0 0 90)
			(layer "F.SilkS")
			(hide yes)
			(effects
				(font
					(size 1.27 1.27)
				)
			)
		)
		(property "Value" ""
			(at 0 0 90)
			(layer "F.Fab")
			(effects
				(font
					(size 1.27 1.27)
				)
			)
		)
		(duplicate_pad_numbers_are_jumpers no)
		(fp_line
			(start 0.299974 -0.150114)
			(end 0.299974 0.150114)
			(stroke
				(width 0.1)
				(type default)
			)
			(layer "F.Fab")
		)
		(fp_line
			(start -0.299974 -0.150114)
			(end 0.299974 -0.150114)
			(stroke
				(width 0.1)
				(type default)
			)
			(layer "F.Fab")
		)
		(fp_line
			(start 0.299974 0.150114)
			(end -0.299974 0.150114)
			(stroke
				(width 0.1)
				(type default)
			)
			(layer "F.Fab")
		)
		(fp_line
			(start -0.299974 0.150114)
			(end -0.299974 -0.150114)
			(stroke
				(width 0.1)
				(type default)
			)
			(layer "F.Fab")
		)
		(pad "1" smd rect
			(at -0.2667 0 90)
			(size 0.3048 0.381)
			(layers "F.Cu" "F.Mask" "F.Paste")
			(net "P5E_PEX1_STN5_TX_DN<81>")
		)
		(pad "2" smd rect
			(at 0.2667 0 90)
			(size 0.3048 0.381)
			(layers "F.Cu" "F.Mask" "F.Paste")
			(net "P5E_PEX1_STN5_TX_C_DN<81>")
		)
	)
	(footprint ""
		(layer "F.Cu")
		(at 420.73449 -30.94609 180)
		(property "Reference" "C718"
			(at 0 0 180)
			(layer "F.SilkS")
			(hide yes)
			(effects
				(font
					(size 1.27 1.27)
				)
			)
		)
		(property "Value" ""
			(at 0 0 180)
			(layer "F.Fab")
			(effects
				(font
					(size 1.27 1.27)
				)
			)
		)
		(duplicate_pad_numbers_are_jumpers no)
		(fp_line
			(start 0.299974 0.150114)
			(end -0.299974 0.150114)
			(stroke
				(width 0.1)
				(type default)
			)
			(layer "F.Fab")
		)
		(fp_line
			(start 0.299974 -0.150114)
			(end 0.299974 0.150114)
			(stroke
				(width 0.1)
				(type default)
			)
			(layer "F.Fab")
		)
		(fp_line
			(start -0.299974 0.150114)
			(end -0.299974 -0.150114)
			(stroke
				(width 0.1)
				(type default)
			)
			(layer "F.Fab")
		)
		(fp_line
			(start -0.299974 -0.150114)
			(end 0.299974 -0.150114)
			(stroke
				(width 0.1)
				(type default)
			)
			(layer "F.Fab")
		)
		(pad "1" smd rect
			(at -0.2667 0 180)
			(size 0.3048 0.381)
			(layers "F.Cu" "F.Mask" "F.Paste")
			(net "P5E_PEX3_STN2_TX_DP<37>")
		)
		(pad "2" smd rect
			(at 0.2667 0 180)
			(size 0.3048 0.381)
			(layers "F.Cu" "F.Mask" "F.Paste")
			(net "P5E_PEX3_STN2_TX_C_DP<37>")
		)
	)
	(footprint ""
		(layer "F.Cu")
		(at 30.979872 -310.28894 -135)
		(property "Reference" "R1111"
			(at 0 0 225)
			(layer "F.SilkS")
			(hide yes)
			(effects
				(font
					(size 1.27 1.27)
				)
			)
		)
		(property "Value" ""
			(at 0 0 225)
			(layer "F.Fab")
			(effects
				(font
					(size 1.27 1.27)
				)
			)
		)
		(duplicate_pad_numbers_are_jumpers no)
		(fp_line
			(start 0.787389 0.406267)
			(end -0.787389 0.406267)
			(stroke
				(width 0.1524)
				(type default)
			)
			(layer "F.SilkS")
		)
		(fp_line
			(start 0.787389 -0.406267)
			(end 0.787389 0.406267)
			(stroke
				(width 0.1524)
				(type default)
			)
			(layer "F.SilkS")
		)
		(fp_line
			(start -0.787389 0.406267)
			(end -0.787389 -0.406267)
			(stroke
				(width 0.1524)
				(type default)
			)
			(layer "F.SilkS")
		)
		(fp_line
			(start -0.787389 -0.406267)
			(end 0.787389 -0.406267)
			(stroke
				(width 0.1524)
				(type default)
			)
			(layer "F.SilkS")
		)
		(fp_line
			(start 0.679446 0.30479)
			(end 0.120515 0.30479)
			(stroke
				(width 0.1)
				(type default)
			)
			(layer "F.Fab")
		)
		(fp_line
			(start 0.120515 0.30479)
			(end 0.120335 0.279466)
			(stroke
				(width 0.1)
				(type default)
			)
			(layer "F.Fab")
		)
		(fp_line
			(start 0.120335 0.279466)
			(end -0.120695 0.279466)
			(stroke
				(width 0.1)
				(type default)
			)
			(layer "F.Fab")
		)
		(fp_line
			(start 0.679446 -0.30479)
			(end 0.679446 0.30479)
			(stroke
				(width 0.1)
				(type default)
			)
			(layer "F.Fab")
		)
		(fp_line
			(start -0.120515 0.30479)
			(end -0.679446 0.30479)
			(stroke
				(width 0.1)
				(type default)
			)
			(layer "F.Fab")
		)
		(fp_line
			(start -0.120695 0.279466)
			(end -0.120515 0.30479)
			(stroke
				(width 0.1)
				(type default)
			)
			(layer "F.Fab")
		)
		(fp_line
			(start 0.120695 -0.279466)
			(end 0.120515 -0.30479)
			(stroke
				(width 0.1)
				(type default)
			)
			(layer "F.Fab")
		)
		(fp_line
			(start 0.120515 -0.30479)
			(end 0.679446 -0.30479)
			(stroke
				(width 0.1)
				(type default)
			)
			(layer "F.Fab")
		)
		(fp_line
			(start -0.679446 0.30479)
			(end -0.679446 -0.305149)
			(stroke
				(width 0.1)
				(type default)
			)
			(layer "F.Fab")
		)
		(fp_line
			(start -0.120695 -0.279466)
			(end 0.120695 -0.279466)
			(stroke
				(width 0.1)
				(type default)
			)
			(layer "F.Fab")
		)
		(fp_line
			(start -0.120695 -0.304969)
			(end -0.120695 -0.279466)
			(stroke
				(width 0.1)
				(type default)
			)
			(layer "F.Fab")
		)
		(fp_line
			(start -0.679446 -0.305149)
			(end -0.120695 -0.304969)
			(stroke
				(width 0.1)
				(type default)
			)
			(layer "F.Fab")
		)
		(pad "1" smd circle
			(at -0.40005 0 225)
			(size 0 0)
			(layers "F.Cu" "F.Mask" "F.Paste")
			(net "PEX0_DBG_MODE0")
		)
		(pad "2" smd circle
			(at 0.40005 0 225)
			(size 0 0)
			(layers "F.Cu" "F.Mask" "F.Paste")
			(net "P1V8_PEX")
		)
	)
	(footprint ""
		(layer "F.Cu")
		(at 114.945668 -343.952322 90)
		(property "Reference" "C358"
			(at 0 0 90)
			(layer "F.SilkS")
			(hide yes)
			(effects
				(font
					(size 1.27 1.27)
				)
			)
		)
		(property "Value" ""
			(at 0 0 90)
			(layer "F.Fab")
			(effects
				(font
					(size 1.27 1.27)
				)
			)
		)
		(duplicate_pad_numbers_are_jumpers no)
		(fp_line
			(start 0.299974 -0.150114)
			(end 0.299974 0.150114)
			(stroke
				(width 0.1)
				(type default)
			)
			(layer "F.Fab")
		)
		(fp_line
			(start -0.299974 -0.150114)
			(end 0.299974 -0.150114)
			(stroke
				(width 0.1)
				(type default)
			)
			(layer "F.Fab")
		)
		(fp_line
			(start 0.299974 0.150114)
			(end -0.299974 0.150114)
			(stroke
				(width 0.1)
				(type default)
			)
			(layer "F.Fab")
		)
		(fp_line
			(start -0.299974 0.150114)
			(end -0.299974 -0.150114)
			(stroke
				(width 0.1)
				(type default)
			)
			(layer "F.Fab")
		)
		(pad "1" smd rect
			(at -0.2667 0 90)
			(size 0.3048 0.381)
			(layers "F.Cu" "F.Mask" "F.Paste")
			(net "P5E_PEX1_STN6_TX_DP<102>")
		)
		(pad "2" smd rect
			(at 0.2667 0 90)
			(size 0.3048 0.381)
			(layers "F.Cu" "F.Mask" "F.Paste")
			(net "P5E_PEX1_STN6_TX_C_DP<102>")
		)
	)
	(footprint ""
		(layer "F.Cu")
		(at 17.358868 -251.082556 -90)
		(property "Reference" "C4230"
			(at 0 0 270)
			(layer "F.SilkS")
			(hide yes)
			(effects
				(font
					(size 1.27 1.27)
				)
			)
		)
		(property "Value" ""
			(at 0 0 270)
			(layer "F.Fab")
			(effects
				(font
					(size 1.27 1.27)
				)
			)
		)
		(duplicate_pad_numbers_are_jumpers no)
		(fp_line
			(start -1.524 0.762)
			(end -1.524 -0.762)
			(stroke
				(width 0.1524)
				(type default)
			)
			(layer "F.SilkS")
		)
		(fp_line
			(start 1.524 0.762)
			(end -1.524 0.762)
			(stroke
				(width 0.1524)
				(type default)
			)
			(layer "F.SilkS")
		)
		(fp_line
			(start -1.524 -0.762)
			(end 1.524 -0.762)
			(stroke
				(width 0.1524)
				(type default)
			)
			(layer "F.SilkS")
		)
		(fp_line
			(start 1.524 -0.762)
			(end 1.524 0.762)
			(stroke
				(width 0.1524)
				(type default)
			)
			(layer "F.SilkS")
		)
		(fp_line
			(start -1.1049 0.724916)
			(end 1.1049 0.724916)
			(stroke
				(width 0.1)
				(type default)
			)
			(layer "F.Fab")
		)
		(fp_line
			(start 1.1049 0.724916)
			(end 1.1049 -0.724916)
			(stroke
				(width 0.1)
				(type default)
			)
			(layer "F.Fab")
		)
		(fp_line
			(start -1.1049 -0.724916)
			(end -1.1049 0.724916)
			(stroke
				(width 0.1)
				(type default)
			)
			(layer "F.Fab")
		)
		(fp_line
			(start 1.1049 -0.724916)
			(end -1.1049 -0.724916)
			(stroke
				(width 0.1)
				(type default)
			)
			(layer "F.Fab")
		)
		(pad "1" smd rect
			(at -0.889 0 90)
			(size 1.016 1.27)
			(layers "F.Cu" "F.Mask" "F.Paste")
			(net "P1V25_SERDES_VDDPLL_PEX0_C4")
		)
		(pad "2" smd rect
			(at 0.889 0 90)
			(size 1.016 1.27)
			(layers "F.Cu" "F.Mask" "F.Paste")
			(net "GND")
		)
		(zone
			(layer "F.Cu")
			(hatch none 0.5)
			(connect_pads
				(clearance 0)
			)
			(min_thickness 0.25)
			(keepout
				(tracks not_allowed)
				(vias allowed)
				(pads allowed)
				(copperpour not_allowed)
				(footprints allowed)
			)
			(placement
				(enabled no)
				(sheetname "")
			)
			(fill
				(thermal_gap 0.5)
				(thermal_bridge_width 0.5)
				(island_removal_mode 0)
			)
			(polygon
				(pts
					(xy 18.083784 -251.412756) (xy 16.633952 -251.412756) (xy 16.633952 -250.752356) (xy 18.083784 -250.752356)
				)
			)
		)
	)
	(footprint ""
		(layer "F.Cu")
		(at 122.077988 -350.098614 90)
		(property "Reference" "C349"
			(at 0 0 90)
			(layer "F.SilkS")
			(hide yes)
			(effects
				(font
					(size 1.27 1.27)
				)
			)
		)
		(property "Value" ""
			(at 0 0 90)
			(layer "F.Fab")
			(effects
				(font
					(size 1.27 1.27)
				)
			)
		)
		(duplicate_pad_numbers_are_jumpers no)
		(fp_line
			(start 0.299974 -0.150114)
			(end 0.299974 0.150114)
			(stroke
				(width 0.1)
				(type default)
			)
			(layer "F.Fab")
		)
		(fp_line
			(start -0.299974 -0.150114)
			(end 0.299974 -0.150114)
			(stroke
				(width 0.1)
				(type default)
			)
			(layer "F.Fab")
		)
		(fp_line
			(start 0.299974 0.150114)
			(end -0.299974 0.150114)
			(stroke
				(width 0.1)
				(type default)
			)
			(layer "F.Fab")
		)
		(fp_line
			(start -0.299974 0.150114)
			(end -0.299974 -0.150114)
			(stroke
				(width 0.1)
				(type default)
			)
			(layer "F.Fab")
		)
		(pad "1" smd rect
			(at -0.2667 0 90)
			(size 0.3048 0.381)
			(layers "F.Cu" "F.Mask" "F.Paste")
			(net "P5E_PEX1_STN6_TX_DN<107>")
		)
		(pad "2" smd rect
			(at 0.2667 0 90)
			(size 0.3048 0.381)
			(layers "F.Cu" "F.Mask" "F.Paste")
			(net "P5E_PEX1_STN6_TX_C_DN<107>")
		)
	)
)
